FILE_TYPE = MULTI_PHYS_TABLE;

PART 'XC7A200T_2FBG484C_FBG484'
CLASS=IC

{========================================================================================}
:CLS_PN          = JEDEC_TYPE              | ALT_SYMBOLS               | DESCRIPTION                                           | CPN_STATUS ;
{========================================================================================}
 'G240-10028-01' = 'BGA484_906_P0394_H100' | '(BGA484_906_P0394_H100)' | 'IC,FPGA,XC7A200T-2FBG484C, ARTIX-7, 23X23,FBG484'    | ''        
 'G240-10063-01' = 'BGA484_906_P0394_V3'   | '(BGA484_906_P0394_V3)'   | 'IC,FPGA,XC7A75T-2FGG484C,0.95V,FGG484 XILINX(168AO)' | ''        
 'G240-10069-01' = 'BGA484_906_P0394_V3'   | '(BGA484_906_P0394_V3)'   | 'IC,FPGA,ARTIX-7,XC7A100T-1FGG484I,FGG484'            | ''        

END_PART

END.

